(kicad_pcb
	(version 20260206)
	(generator "pcbnew")
	(generator_version "10.0")
	(general
		(thickness 1.6)
		(legacy_teardrops no)
	)
	(paper "A4")
	(title_block
		(title "Wiwynn_Tioga_Pass_MB.brd")
		(comment 1 "Tioga Pass / footprints 2552-2558 of 4770")
	)
	(layers
		(0 "F.Cu" signal "TOP")
		(4 "In1.Cu" signal "L2GND")
		(6 "In2.Cu" signal "L3")
		(8 "In3.Cu" signal "L4GND")
		(10 "In4.Cu" signal "L5")
		(12 "In5.Cu" signal "L6GND")
		(14 "In6.Cu" signal "L7VCC")
		(16 "In7.Cu" signal "L8VCC")
		(18 "In8.Cu" signal "L9GND")
		(20 "In9.Cu" signal "L10")
		(22 "In10.Cu" signal "L11GND")
		(24 "In11.Cu" signal "L12")
		(26 "In12.Cu" signal "L13GND")
		(2 "B.Cu" signal "BOTTOM")
		(9 "F.Adhes" user "F.Adhesive")
		(11 "B.Adhes" user "B.Adhesive")
		(13 "F.Paste" user "Package Geometry/Pastemask Top")
		(15 "B.Paste" user "Package Geometry/Pastemask Bottom")
		(5 "F.SilkS" user "Ref Des/Silkscreen Top")
		(7 "B.SilkS" user "Ref Des/Silkscreen Bottom")
		(1 "F.Mask" user "Board Geometry/Soldermask Top")
		(3 "B.Mask" user "Board Geometry/Soldermask Bottom")
		(17 "Dwgs.User" user "User.Drawings")
		(19 "Cmts.User" user "User.Comments")
		(21 "Eco1.User" user "User.Eco1")
		(23 "Eco2.User" user "User.Eco2")
		(25 "Edge.Cuts" user "Board Geometry/Outline")
		(27 "Margin" user)
		(31 "F.CrtYd" user "Package Geometry/Place Bound Top")
		(29 "B.CrtYd" user "Package Geometry/Place Bound Bottom")
		(35 "F.Fab" user "Ref Des/Assembly Top")
		(33 "B.Fab" user "Ref Des/Assembly Bottom")
	)
	(footprint ""
		(layer "B.Cu")
		(at 266.397232 -8.1534 90)
		(property "Reference" "C5U5"
			(at -1.848866 0.752348 90)
			(unlocked yes)
			(layer "B.SilkS")
			(effects
				(font
					(size 1.27 0.9652)
					(thickness 0.1524)
				)
				(justify mirror)
			)
		)
		(property "Value" ""
			(at 0 0 90)
			(layer "B.Fab")
			(effects
				(font
					(size 1.27 1.27)
				)
				(justify mirror)
			)
		)
		(duplicate_pad_numbers_are_jumpers no)
		(fp_rect
			(start 0.500126 1.598422)
			(end -0.500126 -0.201422)
			(stroke
				(width 0)
				(type default)
			)
			(fill no)
			(layer "B.CrtYd")
		)
		(fp_line
			(start 0.500126 -0.201422)
			(end -0.500126 -0.201422)
			(stroke
				(width 0.1)
				(type default)
			)
			(layer "B.Fab")
		)
		(fp_line
			(start -0.500126 -0.201422)
			(end -0.500126 1.598422)
			(stroke
				(width 0.1)
				(type default)
			)
			(layer "B.Fab")
		)
		(fp_line
			(start 0.500126 1.598422)
			(end 0.500126 -0.201422)
			(stroke
				(width 0.1)
				(type default)
			)
			(layer "B.Fab")
		)
		(fp_line
			(start -0.500126 1.598422)
			(end 0.500126 1.598422)
			(stroke
				(width 0.1)
				(type default)
			)
			(layer "B.Fab")
		)
		(pad "1" smd rect
			(at 0 0)
			(size 0.889 0.9906)
			(layers "B.Cu" "B.Mask" "B.Paste")
			(net "PVDDQ_ABC")
		)
		(pad "2" smd rect
			(at 0 1.397)
			(size 0.889 0.9906)
			(layers "B.Cu" "B.Mask" "B.Paste")
			(net "GND")
		)
		(zone
			(layer "B.Cu")
			(hatch none 0.5)
			(connect_pads
				(clearance 0)
			)
			(min_thickness 0.25)
			(keepout
				(tracks allowed)
				(vias not_allowed)
				(pads allowed)
				(copperpour not_allowed)
				(footprints allowed)
			)
			(placement
				(enabled no)
				(sheetname "")
			)
			(fill
				(thermal_gap 0.5)
				(thermal_bridge_width 0.5)
				(island_removal_mode 0)
			)
			(polygon
				(pts
					(xy 267.349732 -8.6487) (xy 266.841732 -8.6487) (xy 266.841732 -7.6581) (xy 267.349732 -7.6581)
				)
			)
		)
		(zone
			(layer "B.Cu")
			(hatch none 0.5)
			(connect_pads
				(clearance 0)
			)
			(min_thickness 0.25)
			(keepout
				(tracks not_allowed)
				(vias allowed)
				(pads allowed)
				(copperpour not_allowed)
				(footprints allowed)
			)
			(placement
				(enabled no)
				(sheetname "")
			)
			(fill
				(thermal_gap 0.5)
				(thermal_bridge_width 0.5)
				(island_removal_mode 0)
			)
			(polygon
				(pts
					(xy 267.349732 -8.6487) (xy 266.841732 -8.6487) (xy 266.841732 -7.6581) (xy 267.349732 -7.6581)
				)
			)
		)
	)
	(footprint ""
		(layer "B.Cu")
		(at 327.95718 -58.724546 -90)
		(property "Reference" "R4R5"
			(at 0 0 90)
			(layer "B.SilkS")
			(hide yes)
			(effects
				(font
					(size 1.27 1.27)
				)
				(justify mirror)
			)
		)
		(property "Value" ""
			(at 0 0 90)
			(layer "B.Fab")
			(effects
				(font
					(size 1.27 1.27)
				)
				(justify mirror)
			)
		)
		(duplicate_pad_numbers_are_jumpers no)
		(fp_poly
			(pts
				(xy 0.2794 -0.1016) (xy -0.2794 -0.1016) (xy -0.2794 0.9906) (xy 0.2794 0.9906)
			)
			(stroke
				(width 0)
				(type default)
			)
			(fill no)
			(layer "B.CrtYd")
		)
		(fp_line
			(start -0.2794 0.9906)
			(end -0.2794 -0.1016)
			(stroke
				(width 0.1)
				(type default)
			)
			(layer "B.Fab")
		)
		(fp_line
			(start 0.2794 0.9906)
			(end -0.2794 0.9906)
			(stroke
				(width 0.1)
				(type default)
			)
			(layer "B.Fab")
		)
		(fp_line
			(start -0.2794 -0.1016)
			(end 0.2794 -0.1016)
			(stroke
				(width 0.1)
				(type default)
			)
			(layer "B.Fab")
		)
		(fp_line
			(start 0.2794 -0.1016)
			(end 0.2794 0.9906)
			(stroke
				(width 0.1)
				(type default)
			)
			(layer "B.Fab")
		)
		(pad "1" smd rect
			(at 0 0 90)
			(size 0.508 0.508)
			(layers "B.Cu" "B.Mask" "B.Paste")
			(net "P3V3_STBY")
		)
		(pad "2" smd rect
			(at 0 0.889 90)
			(size 0.508 0.508)
			(layers "B.Cu" "B.Mask" "B.Paste")
			(net "FM_CPU0_SKTOCC_LVT3_N")
		)
		(zone
			(layer "B.Cu")
			(hatch none 0.5)
			(connect_pads
				(clearance 0)
			)
			(min_thickness 0.25)
			(keepout
				(tracks not_allowed)
				(vias allowed)
				(pads allowed)
				(copperpour not_allowed)
				(footprints allowed)
			)
			(placement
				(enabled no)
				(sheetname "")
			)
			(fill
				(thermal_gap 0.5)
				(thermal_bridge_width 0.5)
				(island_removal_mode 0)
			)
			(polygon
				(pts
					(xy 327.32218 -58.470546) (xy 327.32218 -58.978546) (xy 327.70318 -58.978546) (xy 327.70318 -58.470546)
				)
			)
		)
		(zone
			(layer "B.Cu")
			(hatch none 0.5)
			(connect_pads
				(clearance 0)
			)
			(min_thickness 0.25)
			(keepout
				(tracks allowed)
				(vias not_allowed)
				(pads allowed)
				(copperpour not_allowed)
				(footprints allowed)
			)
			(placement
				(enabled no)
				(sheetname "")
			)
			(fill
				(thermal_gap 0.5)
				(thermal_bridge_width 0.5)
				(island_removal_mode 0)
			)
			(polygon
				(pts
					(xy 327.70318 -58.470546) (xy 327.70318 -58.978546) (xy 327.32218 -58.978546) (xy 327.32218 -58.470546)
				)
			)
		)
	)
	(footprint ""
		(layer "B.Cu")
		(at 425.5008 -15.0622 -90)
		(property "Reference" "R9G30"
			(at 0 0 90)
			(layer "B.SilkS")
			(hide yes)
			(effects
				(font
					(size 1.27 1.27)
				)
				(justify mirror)
			)
		)
		(property "Value" ""
			(at 0 0 90)
			(layer "B.Fab")
			(effects
				(font
					(size 1.27 1.27)
				)
				(justify mirror)
			)
		)
		(duplicate_pad_numbers_are_jumpers no)
		(fp_poly
			(pts
				(xy 0.2794 -0.1016) (xy -0.2794 -0.1016) (xy -0.2794 0.9906) (xy 0.2794 0.9906)
			)
			(stroke
				(width 0)
				(type default)
			)
			(fill no)
			(layer "B.CrtYd")
		)
		(fp_line
			(start -0.2794 0.9906)
			(end -0.2794 -0.1016)
			(stroke
				(width 0.1)
				(type default)
			)
			(layer "B.Fab")
		)
		(fp_line
			(start 0.2794 0.9906)
			(end -0.2794 0.9906)
			(stroke
				(width 0.1)
				(type default)
			)
			(layer "B.Fab")
		)
		(fp_line
			(start -0.2794 -0.1016)
			(end 0.2794 -0.1016)
			(stroke
				(width 0.1)
				(type default)
			)
			(layer "B.Fab")
		)
		(fp_line
			(start 0.2794 -0.1016)
			(end 0.2794 0.9906)
			(stroke
				(width 0.1)
				(type default)
			)
			(layer "B.Fab")
		)
		(pad "1" smd rect
			(at 0 0 90)
			(size 0.508 0.508)
			(layers "B.Cu" "B.Mask" "B.Paste")
			(net "H_CPU0_MEMDEF_MEMHOT_LVT3_N")
		)
		(pad "2" smd rect
			(at 0 0.889 90)
			(size 0.508 0.508)
			(layers "B.Cu" "B.Mask" "B.Paste")
			(net "H_CPU0_MEMDEF_MEMHOT_PCH_N")
		)
		(zone
			(layer "B.Cu")
			(hatch none 0.5)
			(connect_pads
				(clearance 0)
			)
			(min_thickness 0.25)
			(keepout
				(tracks not_allowed)
				(vias allowed)
				(pads allowed)
				(copperpour not_allowed)
				(footprints allowed)
			)
			(placement
				(enabled no)
				(sheetname "")
			)
			(fill
				(thermal_gap 0.5)
				(thermal_bridge_width 0.5)
				(island_removal_mode 0)
			)
			(polygon
				(pts
					(xy 424.8658 -14.8082) (xy 424.8658 -15.3162) (xy 425.2468 -15.3162) (xy 425.2468 -14.8082)
				)
			)
		)
		(zone
			(layer "B.Cu")
			(hatch none 0.5)
			(connect_pads
				(clearance 0)
			)
			(min_thickness 0.25)
			(keepout
				(tracks allowed)
				(vias not_allowed)
				(pads allowed)
				(copperpour not_allowed)
				(footprints allowed)
			)
			(placement
				(enabled no)
				(sheetname "")
			)
			(fill
				(thermal_gap 0.5)
				(thermal_bridge_width 0.5)
				(island_removal_mode 0)
			)
			(polygon
				(pts
					(xy 425.2468 -14.8082) (xy 425.2468 -15.3162) (xy 424.8658 -15.3162) (xy 424.8658 -14.8082)
				)
			)
		)
	)
	(footprint ""
		(layer "B.Cu")
		(at 158.6738 -123.8504)
		(property "Reference" "R7M6"
			(at 0 0 0)
			(layer "B.SilkS")
			(hide yes)
			(effects
				(font
					(size 1.27 1.27)
				)
				(justify mirror)
			)
		)
		(property "Value" ""
			(at 0 0 0)
			(layer "B.Fab")
			(effects
				(font
					(size 1.27 1.27)
				)
				(justify mirror)
			)
		)
		(duplicate_pad_numbers_are_jumpers no)
		(fp_poly
			(pts
				(xy 0.2794 -0.1016) (xy -0.2794 -0.1016) (xy -0.2794 0.9906) (xy 0.2794 0.9906)
			)
			(stroke
				(width 0)
				(type default)
			)
			(fill no)
			(layer "B.CrtYd")
		)
		(fp_line
			(start -0.2794 -0.1016)
			(end 0.2794 -0.1016)
			(stroke
				(width 0.1)
				(type default)
			)
			(layer "B.Fab")
		)
		(fp_line
			(start -0.2794 0.9906)
			(end -0.2794 -0.1016)
			(stroke
				(width 0.1)
				(type default)
			)
			(layer "B.Fab")
		)
		(fp_line
			(start 0.2794 -0.1016)
			(end 0.2794 0.9906)
			(stroke
				(width 0.1)
				(type default)
			)
			(layer "B.Fab")
		)
		(fp_line
			(start 0.2794 0.9906)
			(end -0.2794 0.9906)
			(stroke
				(width 0.1)
				(type default)
			)
			(layer "B.Fab")
		)
		(pad "1" smd rect
			(at 0 0 180)
			(size 0.508 0.508)
			(layers "B.Cu" "B.Mask" "B.Paste")
			(net "PVPP_KLM")
		)
		(pad "2" smd rect
			(at 0 0.889 180)
			(size 0.508 0.508)
			(layers "B.Cu" "B.Mask" "B.Paste")
			(net "SMB_DDR_KLM_VPP_SDA_R")
		)
		(zone
			(layer "B.Cu")
			(hatch none 0.5)
			(connect_pads
				(clearance 0)
			)
			(min_thickness 0.25)
			(keepout
				(tracks allowed)
				(vias not_allowed)
				(pads allowed)
				(copperpour not_allowed)
				(footprints allowed)
			)
			(placement
				(enabled no)
				(sheetname "")
			)
			(fill
				(thermal_gap 0.5)
				(thermal_bridge_width 0.5)
				(island_removal_mode 0)
			)
			(polygon
				(pts
					(xy 158.9278 -123.5964) (xy 158.4198 -123.5964) (xy 158.4198 -123.2154) (xy 158.9278 -123.2154)
				)
			)
		)
		(zone
			(layer "B.Cu")
			(hatch none 0.5)
			(connect_pads
				(clearance 0)
			)
			(min_thickness 0.25)
			(keepout
				(tracks not_allowed)
				(vias allowed)
				(pads allowed)
				(copperpour not_allowed)
				(footprints allowed)
			)
			(placement
				(enabled no)
				(sheetname "")
			)
			(fill
				(thermal_gap 0.5)
				(thermal_bridge_width 0.5)
				(island_removal_mode 0)
			)
			(polygon
				(pts
					(xy 158.9278 -123.2154) (xy 158.4198 -123.2154) (xy 158.4198 -123.5964) (xy 158.9278 -123.5964)
				)
			)
		)
	)
	(footprint ""
		(layer "B.Cu")
		(at 227.584 -91.059 90)
		(property "Reference" "R5N4"
			(at 0 0 90)
			(layer "B.SilkS")
			(hide yes)
			(effects
				(font
					(size 1.27 1.27)
				)
				(justify mirror)
			)
		)
		(property "Value" ""
			(at 0 0 90)
			(layer "B.Fab")
			(effects
				(font
					(size 1.27 1.27)
				)
				(justify mirror)
			)
		)
		(duplicate_pad_numbers_are_jumpers no)
		(fp_poly
			(pts
				(xy 0.2794 -0.1016) (xy -0.2794 -0.1016) (xy -0.2794 0.9906) (xy 0.2794 0.9906)
			)
			(stroke
				(width 0)
				(type default)
			)
			(fill no)
			(layer "B.CrtYd")
		)
		(fp_line
			(start 0.2794 -0.1016)
			(end 0.2794 0.9906)
			(stroke
				(width 0.1)
				(type default)
			)
			(layer "B.Fab")
		)
		(fp_line
			(start -0.2794 -0.1016)
			(end 0.2794 -0.1016)
			(stroke
				(width 0.1)
				(type default)
			)
			(layer "B.Fab")
		)
		(fp_line
			(start 0.2794 0.9906)
			(end -0.2794 0.9906)
			(stroke
				(width 0.1)
				(type default)
			)
			(layer "B.Fab")
		)
		(fp_line
			(start -0.2794 0.9906)
			(end -0.2794 -0.1016)
			(stroke
				(width 0.1)
				(type default)
			)
			(layer "B.Fab")
		)
		(pad "1" smd rect
			(at 0 0 270)
			(size 0.508 0.508)
			(layers "B.Cu" "B.Mask" "B.Paste")
			(net "P3V3_STBY")
		)
		(pad "2" smd rect
			(at 0 0.889 270)
			(size 0.508 0.508)
			(layers "B.Cu" "B.Mask" "B.Paste")
			(net "FM_CPU0_PROC_ID0")
		)
		(zone
			(layer "B.Cu")
			(hatch none 0.5)
			(connect_pads
				(clearance 0)
			)
			(min_thickness 0.25)
			(keepout
				(tracks allowed)
				(vias not_allowed)
				(pads allowed)
				(copperpour not_allowed)
				(footprints allowed)
			)
			(placement
				(enabled no)
				(sheetname "")
			)
			(fill
				(thermal_gap 0.5)
				(thermal_bridge_width 0.5)
				(island_removal_mode 0)
			)
			(polygon
				(pts
					(xy 227.838 -91.313) (xy 227.838 -90.805) (xy 228.219 -90.805) (xy 228.219 -91.313)
				)
			)
		)
		(zone
			(layer "B.Cu")
			(hatch none 0.5)
			(connect_pads
				(clearance 0)
			)
			(min_thickness 0.25)
			(keepout
				(tracks not_allowed)
				(vias allowed)
				(pads allowed)
				(copperpour not_allowed)
				(footprints allowed)
			)
			(placement
				(enabled no)
				(sheetname "")
			)
			(fill
				(thermal_gap 0.5)
				(thermal_bridge_width 0.5)
				(island_removal_mode 0)
			)
			(polygon
				(pts
					(xy 228.219 -91.313) (xy 228.219 -90.805) (xy 227.838 -90.805) (xy 227.838 -91.313)
				)
			)
		)
	)
	(footprint ""
		(layer "B.Cu")
		(at 351.1296 -89.865962 90)
		(property "Reference" "R3N22"
			(at 0 0 90)
			(layer "B.SilkS")
			(hide yes)
			(effects
				(font
					(size 1.27 1.27)
				)
				(justify mirror)
			)
		)
		(property "Value" ""
			(at 0 0 90)
			(layer "B.Fab")
			(effects
				(font
					(size 1.27 1.27)
				)
				(justify mirror)
			)
		)
		(duplicate_pad_numbers_are_jumpers no)
		(fp_poly
			(pts
				(xy 0.2794 -0.1016) (xy -0.2794 -0.1016) (xy -0.2794 0.9906) (xy 0.2794 0.9906)
			)
			(stroke
				(width 0)
				(type default)
			)
			(fill no)
			(layer "B.CrtYd")
		)
		(fp_line
			(start 0.2794 -0.1016)
			(end 0.2794 0.9906)
			(stroke
				(width 0.1)
				(type default)
			)
			(layer "B.Fab")
		)
		(fp_line
			(start -0.2794 -0.1016)
			(end 0.2794 -0.1016)
			(stroke
				(width 0.1)
				(type default)
			)
			(layer "B.Fab")
		)
		(fp_line
			(start 0.2794 0.9906)
			(end -0.2794 0.9906)
			(stroke
				(width 0.1)
				(type default)
			)
			(layer "B.Fab")
		)
		(fp_line
			(start -0.2794 0.9906)
			(end -0.2794 -0.1016)
			(stroke
				(width 0.1)
				(type default)
			)
			(layer "B.Fab")
		)
		(pad "1" smd rect
			(at 0 0 270)
			(size 0.508 0.508)
			(layers "B.Cu" "B.Mask" "B.Paste")
			(net "VR_PVCCIO_CPU0_XADDR2")
		)
		(pad "2" smd rect
			(at 0 0.889 270)
			(size 0.508 0.508)
			(layers "B.Cu" "B.Mask" "B.Paste")
			(net "GND")
		)
		(zone
			(layer "B.Cu")
			(hatch none 0.5)
			(connect_pads
				(clearance 0)
			)
			(min_thickness 0.25)
			(keepout
				(tracks allowed)
				(vias not_allowed)
				(pads allowed)
				(copperpour not_allowed)
				(footprints allowed)
			)
			(placement
				(enabled no)
				(sheetname "")
			)
			(fill
				(thermal_gap 0.5)
				(thermal_bridge_width 0.5)
				(island_removal_mode 0)
			)
			(polygon
				(pts
					(xy 351.3836 -90.119962) (xy 351.3836 -89.611962) (xy 351.7646 -89.611962) (xy 351.7646 -90.119962)
				)
			)
		)
		(zone
			(layer "B.Cu")
			(hatch none 0.5)
			(connect_pads
				(clearance 0)
			)
			(min_thickness 0.25)
			(keepout
				(tracks not_allowed)
				(vias allowed)
				(pads allowed)
				(copperpour not_allowed)
				(footprints allowed)
			)
			(placement
				(enabled no)
				(sheetname "")
			)
			(fill
				(thermal_gap 0.5)
				(thermal_bridge_width 0.5)
				(island_removal_mode 0)
			)
			(polygon
				(pts
					(xy 351.7646 -90.119962) (xy 351.7646 -89.611962) (xy 351.3836 -89.611962) (xy 351.3836 -90.119962)
				)
			)
		)
	)
	(footprint ""
		(layer "B.Cu")
		(at 228.4603 -64.6557 180)
		(property "Reference" "R4E14"
			(at 0 0 0)
			(layer "B.SilkS")
			(hide yes)
			(effects
				(font
					(size 1.27 1.27)
				)
				(justify mirror)
			)
		)
		(property "Value" ""
			(at 0 0 0)
			(layer "B.Fab")
			(effects
				(font
					(size 1.27 1.27)
				)
				(justify mirror)
			)
		)
		(duplicate_pad_numbers_are_jumpers no)
		(fp_poly
			(pts
				(xy 0.2794 -0.1016) (xy -0.2794 -0.1016) (xy -0.2794 0.9906) (xy 0.2794 0.9906)
			)
			(stroke
				(width 0)
				(type default)
			)
			(fill no)
			(layer "B.CrtYd")
		)
		(fp_line
			(start 0.2794 0.9906)
			(end -0.2794 0.9906)
			(stroke
				(width 0.1)
				(type default)
			)
			(layer "B.Fab")
		)
		(fp_line
			(start 0.2794 -0.1016)
			(end 0.2794 0.9906)
			(stroke
				(width 0.1)
				(type default)
			)
			(layer "B.Fab")
		)
		(fp_line
			(start -0.2794 0.9906)
			(end -0.2794 -0.1016)
			(stroke
				(width 0.1)
				(type default)
			)
			(layer "B.Fab")
		)
		(fp_line
			(start -0.2794 -0.1016)
			(end 0.2794 -0.1016)
			(stroke
				(width 0.1)
				(type default)
			)
			(layer "B.Fab")
		)
		(pad "1" smd rect
			(at 0 0)
			(size 0.508 0.508)
			(layers "B.Cu" "B.Mask" "B.Paste")
			(net "VSENSE_PVCCIN_CPU0_P")
		)
		(pad "2" smd rect
			(at 0 0.889)
			(size 0.508 0.508)
			(layers "B.Cu" "B.Mask" "B.Paste")
			(net "PVCCIN_CPU0")
		)
		(zone
			(layer "B.Cu")
			(hatch none 0.5)
			(connect_pads
				(clearance 0)
			)
			(min_thickness 0.25)
			(keepout
				(tracks not_allowed)
				(vias allowed)
				(pads allowed)
				(copperpour not_allowed)
				(footprints allowed)
			)
			(placement
				(enabled no)
				(sheetname "")
			)
			(fill
				(thermal_gap 0.5)
				(thermal_bridge_width 0.5)
				(island_removal_mode 0)
			)
			(polygon
				(pts
					(xy 228.2063 -65.2907) (xy 228.7143 -65.2907) (xy 228.7143 -64.9097) (xy 228.2063 -64.9097)
				)
			)
		)
		(zone
			(layer "B.Cu")
			(hatch none 0.5)
			(connect_pads
				(clearance 0)
			)
			(min_thickness 0.25)
			(keepout
				(tracks allowed)
				(vias not_allowed)
				(pads allowed)
				(copperpour not_allowed)
				(footprints allowed)
			)
			(placement
				(enabled no)
				(sheetname "")
			)
			(fill
				(thermal_gap 0.5)
				(thermal_bridge_width 0.5)
				(island_removal_mode 0)
			)
			(polygon
				(pts
					(xy 228.2063 -64.9097) (xy 228.7143 -64.9097) (xy 228.7143 -65.2907) (xy 228.2063 -65.2907)
				)
			)
		)
	)
)
